# S9S_MB_2U (Grand Teton) — schematic netlist excerpt (pin names and nets, part order shuffled) for the footprints in the layout excerpt that follows; sources: Cadence DE-HDL packaged netlist, KiCad conversion of 03242023_DA0F0TMBIJ0_F0T_Motherboard_J_brd_V01_OCP.brd

H75  HOLE  EMPTY  pkg TH  page 311 : \1\ = NC

(kicad_pcb
	(version 20260206)
	(generator "pcbnew")
	(generator_version "10.0")
	(general
		(thickness 1.6)
		(legacy_teardrops no)
	)
	(paper "A4")
	(title_block
		(title "03242023_DA0F0TMBIJ0_F0T_Motherboard_J_brd_V01_OCP.brd")
		(comment 1 "Grand Teton / footprints 689-689 of 6105")
	)
	(layers
		(0 "F.Cu" signal "TOP")
		(4 "In1.Cu" signal "GND")
		(6 "In2.Cu" signal "IN1")
		(8 "In3.Cu" signal "GND1")
		(10 "In4.Cu" signal "IN2")
		(12 "In5.Cu" signal "GND2")
		(14 "In6.Cu" signal "IN3")
		(16 "In7.Cu" signal "GND3")
		(18 "In8.Cu" signal "VCC")
		(20 "In9.Cu" signal "VCC1")
		(22 "In10.Cu" signal "GND4")
		(24 "In11.Cu" signal "IN4")
		(26 "In12.Cu" signal "GND5")
		(28 "In13.Cu" signal "IN5")
		(30 "In14.Cu" signal "GND6")
		(32 "In15.Cu" signal "IN6")
		(34 "In16.Cu" signal "GND7")
		(2 "B.Cu" signal "BOTTOM")
		(9 "F.Adhes" user "F.Adhesive")
		(11 "B.Adhes" user "B.Adhesive")
		(13 "F.Paste" user "Package Geometry/Pastemask Top")
		(15 "B.Paste" user "Package Geometry/Pastemask Bottom")
		(5 "F.SilkS" user "Ref Des/Silkscreen Top")
		(7 "B.SilkS" user "Ref Des/Silkscreen Bottom")
		(1 "F.Mask" user "Board Geometry/Soldermask Top")
		(3 "B.Mask" user "Board Geometry/Soldermask Bottom")
		(17 "Dwgs.User" user "User.Drawings")
		(19 "Cmts.User" user "User.Comments")
		(21 "Eco1.User" user "User.Eco1")
		(23 "Eco2.User" user "User.Eco2")
		(25 "Edge.Cuts" user "Board Geometry/Outline")
		(27 "Margin" user)
		(31 "F.CrtYd" user "Package Geometry/Place Bound Top")
		(29 "B.CrtYd" user "Package Geometry/Place Bound Bottom")
		(35 "F.Fab" user "Ref Des/Assembly Top")
		(33 "B.Fab" user "Ref Des/Assembly Bottom")
	)
	(footprint ""
		(layer "F.Cu")
		(at 63.582804 -47.049944 90)
		(property "Reference" "H75"
			(at 4.323137 -0.070988 358.089)
			(unlocked yes)
			(layer "F.SilkS")
			(effects
				(font
					(size 0.7874 0.5842)
					(thickness 0.1524)
				)
			)
		)
		(property "Value" ""
			(at 0 0 90)
			(layer "F.Fab")
			(effects
				(font
					(size 1.27 1.27)
				)
			)
		)
		(duplicate_pad_numbers_are_jumpers no)
		(pad "" np_thru_hole circle
			(at 0 0 90)
			(size 0 0)
			(drill oval 3.2004 4.8006)
			(layers "*.Cu" "*.Mask")
			(clearance -1.2192)
			(thermal_gap 0.381)
			(padstack
				(mode front_inner_back)
				(layer "Inner"
					(shape oval)
					(size 3.2004 4.8006)
					(clearance 0.381)
				)
				(layer "B.Cu"
					(shape circle)
					(size 0 0)
					(clearance -1.2192)
				)
			)
		)
		(zone
			(layers "F.Cu" "B.Cu" "In1.Cu" "In2.Cu" "In3.Cu" "In4.Cu" "In5.Cu" "In6.Cu"
				"In7.Cu" "In8.Cu" "In9.Cu" "In10.Cu" "In11.Cu" "In12.Cu" "In13.Cu" "In14.Cu"
				"In15.Cu" "In16.Cu"
			)
			(hatch none 0.5)
			(connect_pads
				(clearance 0)
			)
			(min_thickness 0.25)
			(keepout
				(tracks not_allowed)
				(vias allowed)
				(pads allowed)
				(copperpour not_allowed)
				(footprints allowed)
			)
			(placement
				(enabled no)
				(sheetname "")
			)
			(fill
				(thermal_gap 0.5)
				(thermal_bridge_width 0.5)
				(island_removal_mode 0)
			)
			(polygon
				(pts
					(arc
						(start 64.38265 -49.158144)
						(mid 66.49085 -47.049944)
						(end 64.38265 -44.941744)
					)
					(arc
						(start 62.782958 -44.941744)
						(mid 60.674758 -47.049944)
						(end 62.782958 -49.158144)
					)
				)
			)
		)
		(zone
			(layers "F.Cu" "B.Cu" "In1.Cu" "In2.Cu" "In3.Cu" "In4.Cu" "In5.Cu" "In6.Cu"
				"In7.Cu" "In8.Cu" "In9.Cu" "In10.Cu" "In11.Cu" "In12.Cu" "In13.Cu" "In14.Cu"
				"In15.Cu" "In16.Cu"
			)
			(hatch none 0.5)
			(connect_pads
				(clearance 0)
			)
			(min_thickness 0.25)
			(keepout
				(tracks not_allowed)
				(vias allowed)
				(pads allowed)
				(copperpour not_allowed)
				(footprints allowed)
			)
			(placement
				(enabled no)
				(sheetname "")
			)
			(fill
				(thermal_gap 0.5)
				(thermal_bridge_width 0.5)
				(island_removal_mode 0)
			)
			(polygon
				(pts
					(arc
						(start 64.382904 -50.050192)
						(mid 67.383152 -47.050071)
						(end 64.383158 -44.049696)
					)
					(arc
						(start 62.782704 -44.049696)
						(mid 59.782456 -47.049817)
						(end 62.78245 -50.050192)
					)
				)
			)
		)
	)
)
